(kicad_pcb
	(version 20260206)
	(generator "pcbnew")
	(generator_version "10.0")
	(general
		(thickness 1.6)
		(legacy_teardrops no)
	)
	(paper "A4")
	(title_block
		(title "Bryce Canyon_SCC_16316-1_OCP.brd")
		(comment 1 "Bryce Canyon / footprints 1072-1079 of 1561")
	)
	(layers
		(0 "F.Cu" signal "TOP")
		(4 "In1.Cu" signal "L2GND")
		(6 "In2.Cu" signal "L3")
		(8 "In3.Cu" signal "L4VCC")
		(10 "In4.Cu" signal "L5VCC")
		(12 "In5.Cu" signal "L6")
		(14 "In6.Cu" signal "L7GND")
		(2 "B.Cu" signal "BOTTOM")
		(9 "F.Adhes" user "F.Adhesive")
		(11 "B.Adhes" user "B.Adhesive")
		(13 "F.Paste" user "Package Geometry/Pastemask Top")
		(15 "B.Paste" user "Package Geometry/Pastemask Bottom")
		(5 "F.SilkS" user "Ref Des/Silkscreen Top")
		(7 "B.SilkS" user "Ref Des/Silkscreen Bottom")
		(1 "F.Mask" user "Board Geometry/Soldermask Top")
		(3 "B.Mask" user "Board Geometry/Soldermask Bottom")
		(17 "Dwgs.User" user "User.Drawings")
		(19 "Cmts.User" user "User.Comments")
		(21 "Eco1.User" user "User.Eco1")
		(23 "Eco2.User" user "User.Eco2")
		(25 "Edge.Cuts" user "Board Geometry/Outline")
		(27 "Margin" user)
		(31 "F.CrtYd" user "Package Geometry/Place Bound Top")
		(29 "B.CrtYd" user "Package Geometry/Place Bound Bottom")
		(35 "F.Fab" user "Ref Des/Assembly Top")
		(33 "B.Fab" user "Ref Des/Assembly Bottom")
	)
	(footprint ""
		(layer "B.Cu")
		(at 122.4788 -65.4812 -90)
		(property "Reference" "C285"
			(at 0 0 90)
			(layer "B.SilkS")
			(hide yes)
			(effects
				(font
					(size 1.27 1.27)
				)
				(justify mirror)
			)
		)
		(property "Value" "SCD1U6D3V1KX-GP"
			(at 2.8321 -1.7399 270)
			(unlocked yes)
			(layer "B.Fab")
			(hide yes)
			(effects
				(font
					(size 1.016 1.016)
					(thickness 0.1524)
				)
				(justify mirror)
			)
		)
		(property "Device Type" "C0201H13"
			(at 2.8321 -3.2639 270)
			(unlocked yes)
			(layer "B.Fab")
			(hide yes)
			(effects
				(font
					(size 1.016 1.016)
					(thickness 0.1524)
				)
				(justify mirror)
			)
		)
		(duplicate_pad_numbers_are_jumpers no)
		(fp_rect
			(start 0.2794 0.6477)
			(end -0.2794 -0.6477)
			(stroke
				(width 0)
				(type default)
			)
			(fill no)
			(layer "B.CrtYd")
		)
		(fp_rect
			(start 0.2794 0.6477)
			(end -0.2794 -0.6477)
			(stroke
				(width 0)
				(type default)
			)
			(fill no)
			(layer "B.Fab")
		)
		(pad "1" smd custom
			(at 0 -0.2794 90)
			(size 0.0762 0.0762)
			(layers "B.Cu" "B.Mask" "B.Paste")
			(net "GB_VDDA")
			(options
				(clearance outline)
				(anchor circle)
			)
			(primitives
				(gr_poly
					(pts
						(arc
							(start 0.1524 0.127)
							(mid 0.137521 0.162921)
							(end 0.1016 0.1778)
						)
						(arc
							(start -0.1016 0.1778)
							(mid -0.137521 0.162921)
							(end -0.1524 0.127)
						)
						(arc
							(start -0.1524 -0.127)
							(mid -0.137521 -0.162921)
							(end -0.1016 -0.1778)
						)
						(arc
							(start 0.1016 -0.1778)
							(mid 0.137521 -0.162921)
							(end 0.1524 -0.127)
						)
					)
					(width 0)
					(fill yes)
				)
			)
		)
		(pad "2" smd custom
			(at 0 0.2794 90)
			(size 0.0762 0.0762)
			(layers "B.Cu" "B.Mask" "B.Paste")
			(net "GND")
			(options
				(clearance outline)
				(anchor circle)
			)
			(primitives
				(gr_poly
					(pts
						(arc
							(start 0.1524 0.127)
							(mid 0.137521 0.162921)
							(end 0.1016 0.1778)
						)
						(arc
							(start -0.1016 0.1778)
							(mid -0.137521 0.162921)
							(end -0.1524 0.127)
						)
						(arc
							(start -0.1524 -0.127)
							(mid -0.137521 -0.162921)
							(end -0.1016 -0.1778)
						)
						(arc
							(start 0.1016 -0.1778)
							(mid 0.137521 -0.162921)
							(end 0.1524 -0.127)
						)
					)
					(width 0)
					(fill yes)
				)
			)
		)
	)
	(footprint ""
		(layer "B.Cu")
		(at 101.58222 -84.18322 -90)
		(property "Reference" "R566"
			(at 0 0 90)
			(layer "B.SilkS")
			(hide yes)
			(effects
				(font
					(size 1.27 1.27)
				)
				(justify mirror)
			)
		)
		(property "Value" "10KR2F-2-GP"
			(at -0.064008 -3.993896 270)
			(unlocked yes)
			(layer "B.Fab")
			(hide yes)
			(effects
				(font
					(size 1.016 1.016)
					(thickness 0.1524)
				)
				(justify mirror)
			)
		)
		(property "Device Type" "R402H16"
			(at -0.064008 -5.517896 270)
			(unlocked yes)
			(layer "B.Fab")
			(hide yes)
			(effects
				(font
					(size 1.016 1.016)
					(thickness 0.1524)
				)
				(justify mirror)
			)
		)
		(duplicate_pad_numbers_are_jumpers no)
		(fp_line
			(start -0.508 -0.9398)
			(end 0.508 -0.9398)
			(stroke
				(width 0.1524)
				(type default)
			)
			(layer "B.SilkS")
		)
		(fp_line
			(start 0.508 -0.9398)
			(end 0.508 0.9398)
			(stroke
				(width 0.1524)
				(type default)
			)
			(layer "B.SilkS")
		)
		(fp_rect
			(start 0.508 0.9398)
			(end -0.508 -0.9398)
			(stroke
				(width 0)
				(type default)
			)
			(fill no)
			(layer "B.CrtYd")
		)
		(fp_rect
			(start 0.508 0.9398)
			(end -0.508 -0.9398)
			(stroke
				(width 0)
				(type default)
			)
			(fill no)
			(layer "B.Fab")
		)
		(pad "1" smd custom
			(at 0 -0.4445 90)
			(size 0.1397 0.1397)
			(layers "B.Cu" "B.Mask" "B.Paste")
			(net "ENCL_FAULT_LED_LS")
			(options
				(clearance outline)
				(anchor circle)
			)
			(primitives
				(gr_poly
					(pts
						(arc
							(start -0.1778 0.2794)
							(mid -0.249642 0.249642)
							(end -0.2794 0.1778)
						)
						(arc
							(start -0.2794 -0.1778)
							(mid -0.249642 -0.249642)
							(end -0.1778 -0.2794)
						)
						(arc
							(start 0.1778 -0.2794)
							(mid 0.249642 -0.249642)
							(end 0.2794 -0.1778)
						)
						(arc
							(start 0.2794 0.1778)
							(mid 0.249642 0.249642)
							(end 0.1778 0.2794)
						)
					)
					(width 0)
					(fill yes)
				)
			)
		)
		(pad "2" smd custom
			(at 0 0.4445 90)
			(size 0.1397 0.1397)
			(layers "B.Cu" "B.Mask" "B.Paste")
			(net "GND")
			(options
				(clearance outline)
				(anchor circle)
			)
			(primitives
				(gr_poly
					(pts
						(arc
							(start -0.1778 0.2794)
							(mid -0.249642 0.249642)
							(end -0.2794 0.1778)
						)
						(arc
							(start -0.2794 -0.1778)
							(mid -0.249642 -0.249642)
							(end -0.1778 -0.2794)
						)
						(arc
							(start 0.1778 -0.2794)
							(mid 0.249642 -0.249642)
							(end 0.2794 -0.1778)
						)
						(arc
							(start 0.2794 0.1778)
							(mid 0.249642 0.249642)
							(end 0.1778 0.2794)
						)
					)
					(width 0)
					(fill yes)
				)
			)
		)
	)
	(footprint ""
		(layer "B.Cu")
		(at 109.496606 -67.87896 90)
		(property "Reference" "R476"
			(at 0 0 90)
			(layer "B.SilkS")
			(hide yes)
			(effects
				(font
					(size 1.27 1.27)
				)
				(justify mirror)
			)
		)
		(property "Value" "0R2F-1-GP"
			(at -0.064008 -3.993896 90)
			(unlocked yes)
			(layer "B.Fab")
			(hide yes)
			(effects
				(font
					(size 1.016 1.016)
					(thickness 0.1524)
				)
				(justify mirror)
			)
		)
		(property "Device Type" "R402H16"
			(at -0.064008 -5.517896 90)
			(unlocked yes)
			(layer "B.Fab")
			(hide yes)
			(effects
				(font
					(size 1.016 1.016)
					(thickness 0.1524)
				)
				(justify mirror)
			)
		)
		(duplicate_pad_numbers_are_jumpers no)
		(fp_line
			(start 0.508 -0.9398)
			(end 0.508 0.9398)
			(stroke
				(width 0.1524)
				(type default)
			)
			(layer "B.SilkS")
		)
		(fp_line
			(start -0.508 -0.9398)
			(end 0.508 -0.9398)
			(stroke
				(width 0.1524)
				(type default)
			)
			(layer "B.SilkS")
		)
		(fp_rect
			(start 0.508 0.9398)
			(end -0.508 -0.9398)
			(stroke
				(width 0)
				(type default)
			)
			(fill no)
			(layer "B.CrtYd")
		)
		(fp_rect
			(start 0.508 0.9398)
			(end -0.508 -0.9398)
			(stroke
				(width 0)
				(type default)
			)
			(fill no)
			(layer "B.Fab")
		)
		(pad "1" smd custom
			(at 0 -0.4445 270)
			(size 0.1397 0.1397)
			(layers "B.Cu" "B.Mask" "B.Paste")
			(net "P0V9_VFB")
			(options
				(clearance outline)
				(anchor circle)
			)
			(primitives
				(gr_poly
					(pts
						(arc
							(start -0.1778 0.2794)
							(mid -0.249642 0.249642)
							(end -0.2794 0.1778)
						)
						(arc
							(start -0.2794 -0.1778)
							(mid -0.249642 -0.249642)
							(end -0.1778 -0.2794)
						)
						(arc
							(start 0.1778 -0.2794)
							(mid 0.249642 -0.249642)
							(end 0.2794 -0.1778)
						)
						(arc
							(start 0.2794 0.1778)
							(mid 0.249642 0.249642)
							(end 0.1778 0.2794)
						)
					)
					(width 0)
					(fill yes)
				)
			)
		)
		(pad "2" smd custom
			(at 0 0.4445 270)
			(size 0.1397 0.1397)
			(layers "B.Cu" "B.Mask" "B.Paste")
			(net "P0V9")
			(options
				(clearance outline)
				(anchor circle)
			)
			(primitives
				(gr_poly
					(pts
						(arc
							(start -0.1778 0.2794)
							(mid -0.249642 0.249642)
							(end -0.2794 0.1778)
						)
						(arc
							(start -0.2794 -0.1778)
							(mid -0.249642 -0.249642)
							(end -0.1778 -0.2794)
						)
						(arc
							(start 0.1778 -0.2794)
							(mid 0.249642 -0.249642)
							(end 0.2794 -0.1778)
						)
						(arc
							(start 0.2794 0.1778)
							(mid 0.249642 0.249642)
							(end 0.1778 0.2794)
						)
					)
					(width 0)
					(fill yes)
				)
			)
		)
	)
	(footprint ""
		(layer "B.Cu")
		(at 136.1694 -75.5904 -90)
		(property "Reference" "C7"
			(at 0 0 90)
			(layer "B.SilkS")
			(hide yes)
			(effects
				(font
					(size 1.27 1.27)
				)
				(justify mirror)
			)
		)
		(property "Value" "SCD01U16V1KX-GP"
			(at 2.8321 -1.7399 270)
			(unlocked yes)
			(layer "B.Fab")
			(hide yes)
			(effects
				(font
					(size 1.016 1.016)
					(thickness 0.1524)
				)
				(justify mirror)
			)
		)
		(property "Device Type" "C0201H13"
			(at 2.8321 -3.2639 270)
			(unlocked yes)
			(layer "B.Fab")
			(hide yes)
			(effects
				(font
					(size 1.016 1.016)
					(thickness 0.1524)
				)
				(justify mirror)
			)
		)
		(duplicate_pad_numbers_are_jumpers no)
		(fp_rect
			(start 0.2794 0.6477)
			(end -0.2794 -0.6477)
			(stroke
				(width 0)
				(type default)
			)
			(fill no)
			(layer "B.CrtYd")
		)
		(fp_rect
			(start 0.2794 0.6477)
			(end -0.2794 -0.6477)
			(stroke
				(width 0)
				(type default)
			)
			(fill no)
			(layer "B.Fab")
		)
		(pad "1" smd custom
			(at 0 -0.2794 90)
			(size 0.0762 0.0762)
			(layers "B.Cu" "B.Mask" "B.Paste")
			(net "PHY_CONN_TO_EXP_8_DP")
			(options
				(clearance outline)
				(anchor circle)
			)
			(primitives
				(gr_poly
					(pts
						(arc
							(start 0.1524 0.127)
							(mid 0.137521 0.162921)
							(end 0.1016 0.1778)
						)
						(arc
							(start -0.1016 0.1778)
							(mid -0.137521 0.162921)
							(end -0.1524 0.127)
						)
						(arc
							(start -0.1524 -0.127)
							(mid -0.137521 -0.162921)
							(end -0.1016 -0.1778)
						)
						(arc
							(start 0.1016 -0.1778)
							(mid 0.137521 -0.162921)
							(end 0.1524 -0.127)
						)
					)
					(width 0)
					(fill yes)
				)
			)
		)
		(pad "2" smd custom
			(at 0 0.2794 90)
			(size 0.0762 0.0762)
			(layers "B.Cu" "B.Mask" "B.Paste")
			(net "PHY_CONN_TO_EXP_C_8_DP")
			(options
				(clearance outline)
				(anchor circle)
			)
			(primitives
				(gr_poly
					(pts
						(arc
							(start 0.1524 0.127)
							(mid 0.137521 0.162921)
							(end 0.1016 0.1778)
						)
						(arc
							(start -0.1016 0.1778)
							(mid -0.137521 0.162921)
							(end -0.1524 0.127)
						)
						(arc
							(start -0.1524 -0.127)
							(mid -0.137521 -0.162921)
							(end -0.1016 -0.1778)
						)
						(arc
							(start 0.1016 -0.1778)
							(mid 0.137521 -0.162921)
							(end 0.1524 -0.127)
						)
					)
					(width 0)
					(fill yes)
				)
			)
		)
	)
	(footprint ""
		(layer "B.Cu")
		(at 121.568972 -86.650068)
		(property "Reference" "R74"
			(at 0 0 0)
			(layer "B.SilkS")
			(hide yes)
			(effects
				(font
					(size 1.27 1.27)
				)
				(justify mirror)
			)
		)
		(property "Value" "4K7R2F-GP"
			(at -0.064008 -3.993896 0)
			(unlocked yes)
			(layer "B.Fab")
			(hide yes)
			(effects
				(font
					(size 1.016 1.016)
					(thickness 0.1524)
				)
				(justify mirror)
			)
		)
		(property "Device Type" "R402H16"
			(at -0.064008 -5.517896 0)
			(unlocked yes)
			(layer "B.Fab")
			(hide yes)
			(effects
				(font
					(size 1.016 1.016)
					(thickness 0.1524)
				)
				(justify mirror)
			)
		)
		(duplicate_pad_numbers_are_jumpers no)
		(fp_line
			(start -0.508 -0.9398)
			(end 0.508 -0.9398)
			(stroke
				(width 0.1524)
				(type default)
			)
			(layer "B.SilkS")
		)
		(fp_line
			(start 0.508 -0.9398)
			(end 0.508 0.9398)
			(stroke
				(width 0.1524)
				(type default)
			)
			(layer "B.SilkS")
		)
		(fp_rect
			(start 0.508 0.9398)
			(end -0.508 -0.9398)
			(stroke
				(width 0)
				(type default)
			)
			(fill no)
			(layer "B.CrtYd")
		)
		(fp_rect
			(start 0.508 0.9398)
			(end -0.508 -0.9398)
			(stroke
				(width 0)
				(type default)
			)
			(fill no)
			(layer "B.Fab")
		)
		(pad "1" smd custom
			(at 0 -0.4445 180)
			(size 0.1397 0.1397)
			(layers "B.Cu" "B.Mask" "B.Paste")
			(net "P1V8_E")
			(options
				(clearance outline)
				(anchor circle)
			)
			(primitives
				(gr_poly
					(pts
						(arc
							(start -0.1778 0.2794)
							(mid -0.249642 0.249642)
							(end -0.2794 0.1778)
						)
						(arc
							(start -0.2794 -0.1778)
							(mid -0.249642 -0.249642)
							(end -0.1778 -0.2794)
						)
						(arc
							(start 0.1778 -0.2794)
							(mid 0.249642 -0.249642)
							(end 0.2794 -0.1778)
						)
						(arc
							(start 0.2794 0.1778)
							(mid 0.249642 0.249642)
							(end 0.1778 0.2794)
						)
					)
					(width 0)
					(fill yes)
				)
			)
		)
		(pad "2" smd custom
			(at 0 0.4445 180)
			(size 0.1397 0.1397)
			(layers "B.Cu" "B.Mask" "B.Paste")
			(net "SCC_TYPE_2_LS")
			(options
				(clearance outline)
				(anchor circle)
			)
			(primitives
				(gr_poly
					(pts
						(arc
							(start -0.1778 0.2794)
							(mid -0.249642 0.249642)
							(end -0.2794 0.1778)
						)
						(arc
							(start -0.2794 -0.1778)
							(mid -0.249642 -0.249642)
							(end -0.1778 -0.2794)
						)
						(arc
							(start 0.1778 -0.2794)
							(mid 0.249642 -0.249642)
							(end 0.2794 -0.1778)
						)
						(arc
							(start 0.2794 0.1778)
							(mid 0.249642 0.249642)
							(end 0.1778 0.2794)
						)
					)
					(width 0)
					(fill yes)
				)
			)
		)
	)
	(footprint ""
		(layer "B.Cu")
		(at 179.37353 -46.090332 180)
		(property "Reference" "C407"
			(at 0 0 0)
			(layer "B.SilkS")
			(hide yes)
			(effects
				(font
					(size 1.27 1.27)
				)
				(justify mirror)
			)
		)
		(property "Value" "SC10U6D3V5KX-4GP"
			(at 0.0762 -6.1214 180)
			(unlocked yes)
			(layer "B.Fab")
			(hide yes)
			(effects
				(font
					(size 1.016 1.016)
					(thickness 0.1524)
				)
				(justify mirror)
			)
		)
		(property "Device Type" "C805H58"
			(at 0.0762 -8.1534 180)
			(unlocked yes)
			(layer "B.Fab")
			(hide yes)
			(effects
				(font
					(size 1.016 1.016)
					(thickness 0.1524)
				)
				(justify mirror)
			)
		)
		(duplicate_pad_numbers_are_jumpers no)
		(fp_line
			(start -0.635 0)
			(end 0.635 0)
			(stroke
				(width 0.508)
				(type default)
			)
			(layer "B.SilkS")
		)
		(fp_rect
			(start 0.9652 1.778)
			(end -0.9652 -1.778)
			(stroke
				(width 0)
				(type default)
			)
			(fill no)
			(layer "B.CrtYd")
		)
		(fp_poly
			(pts
				(xy 0.9652 -1.778) (xy -0.9652 -1.778) (xy -0.9652 1.778) (xy 0.9652 1.778)
			)
			(stroke
				(width 0)
				(type default)
			)
			(fill no)
			(layer "B.Fab")
		)
		(pad "1" smd rect
			(at 0 -0.9652)
			(size 1.397 1.143)
			(layers "B.Cu" "B.Mask" "B.Paste")
			(net "P0V975")
		)
		(pad "2" smd rect
			(at 0 0.9652)
			(size 1.397 1.143)
			(layers "B.Cu" "B.Mask" "B.Paste")
			(net "GND")
		)
	)
	(footprint ""
		(layer "B.Cu")
		(at 105.791 -44.2214 180)
		(property "Reference" "C76"
			(at 0 0 0)
			(layer "B.SilkS")
			(hide yes)
			(effects
				(font
					(size 1.27 1.27)
				)
				(justify mirror)
			)
		)
		(property "Value" "SCD01U16V1KX-GP"
			(at 2.8321 -1.7399 180)
			(unlocked yes)
			(layer "B.Fab")
			(hide yes)
			(effects
				(font
					(size 1.016 1.016)
					(thickness 0.1524)
				)
				(justify mirror)
			)
		)
		(property "Device Type" "C0201H13"
			(at 2.8321 -3.2639 180)
			(unlocked yes)
			(layer "B.Fab")
			(hide yes)
			(effects
				(font
					(size 1.016 1.016)
					(thickness 0.1524)
				)
				(justify mirror)
			)
		)
		(duplicate_pad_numbers_are_jumpers no)
		(fp_rect
			(start 0.2794 0.6477)
			(end -0.2794 -0.6477)
			(stroke
				(width 0)
				(type default)
			)
			(fill no)
			(layer "B.CrtYd")
		)
		(fp_rect
			(start 0.2794 0.6477)
			(end -0.2794 -0.6477)
			(stroke
				(width 0)
				(type default)
			)
			(fill no)
			(layer "B.Fab")
		)
		(pad "1" smd custom
			(at 0 -0.2794)
			(size 0.0762 0.0762)
			(layers "B.Cu" "B.Mask" "B.Paste")
			(net "PHY_DPB_TO_SCC_22_DN")
			(options
				(clearance outline)
				(anchor circle)
			)
			(primitives
				(gr_poly
					(pts
						(arc
							(start 0.1524 0.127)
							(mid 0.137521 0.162921)
							(end 0.1016 0.1778)
						)
						(arc
							(start -0.1016 0.1778)
							(mid -0.137521 0.162921)
							(end -0.1524 0.127)
						)
						(arc
							(start -0.1524 -0.127)
							(mid -0.137521 -0.162921)
							(end -0.1016 -0.1778)
						)
						(arc
							(start 0.1016 -0.1778)
							(mid 0.137521 -0.162921)
							(end 0.1524 -0.127)
						)
					)
					(width 0)
					(fill yes)
				)
			)
		)
		(pad "2" smd custom
			(at 0 0.2794)
			(size 0.0762 0.0762)
			(layers "B.Cu" "B.Mask" "B.Paste")
			(net "PHY_DPB_TO_SCC_C_22_DN")
			(options
				(clearance outline)
				(anchor circle)
			)
			(primitives
				(gr_poly
					(pts
						(arc
							(start 0.1524 0.127)
							(mid 0.137521 0.162921)
							(end 0.1016 0.1778)
						)
						(arc
							(start -0.1016 0.1778)
							(mid -0.137521 0.162921)
							(end -0.1524 0.127)
						)
						(arc
							(start -0.1524 -0.127)
							(mid -0.137521 -0.162921)
							(end -0.1016 -0.1778)
						)
						(arc
							(start 0.1016 -0.1778)
							(mid 0.137521 -0.162921)
							(end 0.1524 -0.127)
						)
					)
					(width 0)
					(fill yes)
				)
			)
		)
	)
	(footprint ""
		(layer "B.Cu")
		(at 123.2535 -57.4802)
		(property "Reference" "C260"
			(at 0 0 0)
			(layer "B.SilkS")
			(hide yes)
			(effects
				(font
					(size 1.27 1.27)
				)
				(justify mirror)
			)
		)
		(property "Value" "SCD1U6D3V1KX-GP"
			(at 2.8321 -1.7399 0)
			(unlocked yes)
			(layer "B.Fab")
			(hide yes)
			(effects
				(font
					(size 1.016 1.016)
					(thickness 0.1524)
				)
				(justify mirror)
			)
		)
		(property "Device Type" "C0201H13"
			(at 2.8321 -3.2639 0)
			(unlocked yes)
			(layer "B.Fab")
			(hide yes)
			(effects
				(font
					(size 1.016 1.016)
					(thickness 0.1524)
				)
				(justify mirror)
			)
		)
		(duplicate_pad_numbers_are_jumpers no)
		(fp_rect
			(start 0.2794 0.6477)
			(end -0.2794 -0.6477)
			(stroke
				(width 0)
				(type default)
			)
			(fill no)
			(layer "B.CrtYd")
		)
		(fp_rect
			(start 0.2794 0.6477)
			(end -0.2794 -0.6477)
			(stroke
				(width 0)
				(type default)
			)
			(fill no)
			(layer "B.Fab")
		)
		(pad "1" smd custom
			(at 0 -0.2794 180)
			(size 0.0762 0.0762)
			(layers "B.Cu" "B.Mask" "B.Paste")
			(net "GB_VDDA")
			(options
				(clearance outline)
				(anchor circle)
			)
			(primitives
				(gr_poly
					(pts
						(arc
							(start 0.1524 0.127)
							(mid 0.137521 0.162921)
							(end 0.1016 0.1778)
						)
						(arc
							(start -0.1016 0.1778)
							(mid -0.137521 0.162921)
							(end -0.1524 0.127)
						)
						(arc
							(start -0.1524 -0.127)
							(mid -0.137521 -0.162921)
							(end -0.1016 -0.1778)
						)
						(arc
							(start 0.1016 -0.1778)
							(mid 0.137521 -0.162921)
							(end 0.1524 -0.127)
						)
					)
					(width 0)
					(fill yes)
				)
			)
		)
		(pad "2" smd custom
			(at 0 0.2794 180)
			(size 0.0762 0.0762)
			(layers "B.Cu" "B.Mask" "B.Paste")
			(net "GND")
			(options
				(clearance outline)
				(anchor circle)
			)
			(primitives
				(gr_poly
					(pts
						(arc
							(start 0.1524 0.127)
							(mid 0.137521 0.162921)
							(end 0.1016 0.1778)
						)
						(arc
							(start -0.1016 0.1778)
							(mid -0.137521 0.162921)
							(end -0.1524 0.127)
						)
						(arc
							(start -0.1524 -0.127)
							(mid -0.137521 -0.162921)
							(end -0.1016 -0.1778)
						)
						(arc
							(start 0.1016 -0.1778)
							(mid 0.137521 -0.162921)
							(end 0.1524 -0.127)
						)
					)
					(width 0)
					(fill yes)
				)
			)
		)
	)
)
